# T6G (Grand Teton) — schematic netlist excerpt (pin names and nets, part order shuffled) for the footprints in the layout excerpt that follows; sources: Cadence DE-HDL packaged netlist, KiCad conversion of 04192023_DAF0TMB3IC0_F0TG_MB_C_brd_V02_OCP.brd

R3265  Q_RES  4.7K 1% EMPTY  pkg 0402LF  page 111 : A = CLK_GEN2_GPU_FPGA_OE_OR_N ; B = GND

(kicad_pcb
	(version 20260206)
	(generator "pcbnew")
	(generator_version "10.0")
	(general
		(thickness 1.6)
		(legacy_teardrops no)
	)
	(paper "A4")
	(title_block
		(title "04192023_DAF0TMB3IC0_F0TG_MB_C_brd_V02_OCP.brd")
		(comment 1 "Grand Teton / footprints 2351-2351 of 8354")
	)
	(layers
		(0 "F.Cu" signal "TOP")
		(4 "In1.Cu" signal "GND")
		(6 "In2.Cu" signal "IN1")
		(8 "In3.Cu" signal "GND1")
		(10 "In4.Cu" signal "IN2")
		(12 "In5.Cu" signal "GND2")
		(14 "In6.Cu" signal "IN3")
		(16 "In7.Cu" signal "GND3")
		(18 "In8.Cu" signal "VCC")
		(20 "In9.Cu" signal "VCC1")
		(22 "In10.Cu" signal "GND4")
		(24 "In11.Cu" signal "IN4")
		(26 "In12.Cu" signal "GND5")
		(28 "In13.Cu" signal "IN5")
		(30 "In14.Cu" signal "GND6")
		(32 "In15.Cu" signal "IN6")
		(34 "In16.Cu" signal "GND7")
		(2 "B.Cu" signal "BOTTOM")
		(9 "F.Adhes" user "F.Adhesive")
		(11 "B.Adhes" user "B.Adhesive")
		(13 "F.Paste" user "Package Geometry/Pastemask Top")
		(15 "B.Paste" user "Package Geometry/Pastemask Bottom")
		(5 "F.SilkS" user "Ref Des/Silkscreen Top")
		(7 "B.SilkS" user "Ref Des/Silkscreen Bottom")
		(1 "F.Mask" user "Board Geometry/Soldermask Top")
		(3 "B.Mask" user "Board Geometry/Soldermask Bottom")
		(17 "Dwgs.User" user "User.Drawings")
		(19 "Cmts.User" user "User.Comments")
		(21 "Eco1.User" user "User.Eco1")
		(23 "Eco2.User" user "User.Eco2")
		(25 "Edge.Cuts" user "Board Geometry/Outline")
		(27 "Margin" user)
		(31 "F.CrtYd" user "Package Geometry/Place Bound Top")
		(29 "B.CrtYd" user "Package Geometry/Place Bound Bottom")
		(35 "F.Fab" user "Ref Des/Assembly Top")
		(33 "B.Fab" user "Ref Des/Assembly Bottom")
	)
	(footprint ""
		(layer "F.Cu")
		(at 40.494458 -429.790098 -90)
		(property "Reference" "R3265"
			(at 0 0 270)
			(layer "F.SilkS")
			(hide yes)
			(effects
				(font
					(size 1.27 1.27)
				)
			)
		)
		(property "Value" ""
			(at 0 0 270)
			(layer "F.Fab")
			(effects
				(font
					(size 1.27 1.27)
				)
			)
		)
		(duplicate_pad_numbers_are_jumpers no)
		(fp_line
			(start -0.7874 0.4064)
			(end -0.7874 -0.4064)
			(stroke
				(width 0.1524)
				(type default)
			)
			(layer "F.SilkS")
		)
		(fp_line
			(start 0.7874 0.4064)
			(end -0.7874 0.4064)
			(stroke
				(width 0.1524)
				(type default)
			)
			(layer "F.SilkS")
		)
		(fp_line
			(start -0.7874 -0.4064)
			(end 0.7874 -0.4064)
			(stroke
				(width 0.1524)
				(type default)
			)
			(layer "F.SilkS")
		)
		(fp_line
			(start 0.7874 -0.4064)
			(end 0.7874 0.4064)
			(stroke
				(width 0.1524)
				(type default)
			)
			(layer "F.SilkS")
		)
		(fp_line
			(start -0.67945 0.3048)
			(end -0.67945 -0.305054)
			(stroke
				(width 0.1)
				(type default)
			)
			(layer "F.Fab")
		)
		(fp_line
			(start -0.12065 0.3048)
			(end -0.67945 0.3048)
			(stroke
				(width 0.1)
				(type default)
			)
			(layer "F.Fab")
		)
		(fp_line
			(start 0.120396 0.3048)
			(end 0.120396 0.2794)
			(stroke
				(width 0.1)
				(type default)
			)
			(layer "F.Fab")
		)
		(fp_line
			(start 0.67945 0.3048)
			(end 0.120396 0.3048)
			(stroke
				(width 0.1)
				(type default)
			)
			(layer "F.Fab")
		)
		(fp_line
			(start -0.12065 0.2794)
			(end -0.12065 0.3048)
			(stroke
				(width 0.1)
				(type default)
			)
			(layer "F.Fab")
		)
		(fp_line
			(start 0.120396 0.2794)
			(end -0.12065 0.2794)
			(stroke
				(width 0.1)
				(type default)
			)
			(layer "F.Fab")
		)
		(fp_line
			(start -0.12065 -0.2794)
			(end 0.12065 -0.2794)
			(stroke
				(width 0.1)
				(type default)
			)
			(layer "F.Fab")
		)
		(fp_line
			(start 0.12065 -0.2794)
			(end 0.12065 -0.3048)
			(stroke
				(width 0.1)
				(type default)
			)
			(layer "F.Fab")
		)
		(fp_line
			(start 0.12065 -0.3048)
			(end 0.67945 -0.3048)
			(stroke
				(width 0.1)
				(type default)
			)
			(layer "F.Fab")
		)
		(fp_line
			(start 0.67945 -0.3048)
			(end 0.67945 0.3048)
			(stroke
				(width 0.1)
				(type default)
			)
			(layer "F.Fab")
		)
		(fp_line
			(start -0.67945 -0.305054)
			(end -0.12065 -0.305054)
			(stroke
				(width 0.1)
				(type default)
			)
			(layer "F.Fab")
		)
		(fp_line
			(start -0.12065 -0.305054)
			(end -0.12065 -0.2794)
			(stroke
				(width 0.1)
				(type default)
			)
			(layer "F.Fab")
		)
		(pad "1" smd circle
			(at -0.40005 0 270)
			(size 0 0)
			(layers "F.Cu" "F.Mask" "F.Paste")
			(net "CLK_GEN2_GPU_FPGA_OE_OR_N")
		)
		(pad "2" smd circle
			(at 0.40005 0 270)
			(size 0 0)
			(layers "F.Cu" "F.Mask" "F.Paste")
			(net "GND")
		)
	)
)
